(kicad_pcb
	(version 20260206)
	(generator "pcbnew")
	(generator_version "10.0")
	(general
		(thickness 1.6)
		(legacy_teardrops no)
	)
	(paper "A4")
	(title_block
		(title "Bryce Canyon_SCC_16316-1_OCP.brd")
		(comment 1 "Bryce Canyon / footprint 482 of 1561 (U2), pads 239-354 of 896")
	)
	(layers
		(0 "F.Cu" signal "TOP")
		(4 "In1.Cu" signal "L2GND")
		(6 "In2.Cu" signal "L3")
		(8 "In3.Cu" signal "L4VCC")
		(10 "In4.Cu" signal "L5VCC")
		(12 "In5.Cu" signal "L6")
		(14 "In6.Cu" signal "L7GND")
		(2 "B.Cu" signal "BOTTOM")
		(9 "F.Adhes" user "F.Adhesive")
		(11 "B.Adhes" user "B.Adhesive")
		(13 "F.Paste" user "Package Geometry/Pastemask Top")
		(15 "B.Paste" user "Package Geometry/Pastemask Bottom")
		(5 "F.SilkS" user "Ref Des/Silkscreen Top")
		(7 "B.SilkS" user "Ref Des/Silkscreen Bottom")
		(1 "F.Mask" user "Board Geometry/Soldermask Top")
		(3 "B.Mask" user "Board Geometry/Soldermask Bottom")
		(17 "Dwgs.User" user "User.Drawings")
		(19 "Cmts.User" user "User.Comments")
		(21 "Eco1.User" user "User.Eco1")
		(23 "Eco2.User" user "User.Eco2")
		(25 "Edge.Cuts" user "Board Geometry/Outline")
		(27 "Margin" user)
		(31 "F.CrtYd" user "Package Geometry/Place Bound Top")
		(29 "B.CrtYd" user "Package Geometry/Place Bound Bottom")
		(35 "F.Fab" user "Ref Des/Assembly Top")
		(33 "B.Fab" user "Ref Des/Assembly Bottom")
	)
	(footprint ""
		(layer "F.Cu")
		(at 174.999904 -39.99992)
		(property "Reference" "U2"
			(at 0 0 0)
			(layer "F.SilkS")
			(hide yes)
			(effects
				(font
					(size 1.27 1.27)
				)
			)
		)
		(property "Value" "SAS3008C0-1-DB-500020657-1-GP"
			(at -20.374102 -5.0292 0)
			(unlocked yes)
			(layer "F.Fab")
			(hide yes)
			(effects
				(font
					(size 1.016 1.016)
					(thickness 0.1524)
				)
			)
		)
		(property "Device Type" "BGA896D25H78"
			(at -20.374102 -6.5532 0)
			(unlocked yes)
			(layer "F.Fab")
			(hide yes)
			(effects
				(font
					(size 1.016 1.016)
					(thickness 0.1524)
				)
			)
		)
		(duplicate_pad_numbers_are_jumpers no)
		(pad "AH1" smd circle
			(at -11.599926 9.99998)
			(size 0.4064 0.4064)
			(layers "F.Cu" "F.Mask" "F.Paste")
			(net "PHY_IOC_TO_SCC_40_DP")
		)
		(pad "AH2" smd circle
			(at -10.80008 9.99998)
			(size 0.4064 0.4064)
			(layers "F.Cu" "F.Mask" "F.Paste")
			(net "PHY_IOC_TO_SCC_40_DN")
		)
		(pad "AH3" smd circle
			(at -9.99998 9.99998)
			(size 0.4064 0.4064)
			(layers "F.Cu" "F.Mask" "F.Paste")
			(net "GND")
		)
		(pad "AH4" smd circle
			(at -9.19988 9.99998)
			(size 0.3556 0.3556)
			(layers "F.Cu" "F.Mask" "F.Paste")
			(net "PHY_SCC_TO_IOC_C_40_DP")
		)
		(pad "AH5" smd circle
			(at -8.400034 9.99998)
			(size 0.3556 0.3556)
			(layers "F.Cu" "F.Mask" "F.Paste")
			(net "PHY_SCC_TO_IOC_C_40_DN")
		)
		(pad "AH6" smd circle
			(at -7.599934 9.99998)
			(size 0.3556 0.3556)
			(layers "F.Cu" "F.Mask" "F.Paste")
			(net "GND")
		)
		(pad "AH7" smd circle
			(at -6.800088 9.99998)
			(size 0.3556 0.3556)
			(layers "F.Cu" "F.Mask" "F.Paste")
			(net "GND")
		)
		(pad "AH8" smd circle
			(at -5.999988 9.99998)
			(size 0.3556 0.3556)
			(layers "F.Cu" "F.Mask" "F.Paste")
			(net "GND")
		)
		(pad "AH9" smd circle
			(at -5.199888 9.99998)
			(size 0.3556 0.3556)
			(layers "F.Cu" "F.Mask" "F.Paste")
			(net "GND")
		)
		(pad "AH10" smd circle
			(at -4.400042 9.99998)
			(size 0.3556 0.3556)
			(layers "F.Cu" "F.Mask" "F.Paste")
			(net "GND")
		)
		(pad "AH11" smd circle
			(at -3.599942 9.99998)
			(size 0.3556 0.3556)
			(layers "F.Cu" "F.Mask" "F.Paste")
			(net "GND")
		)
		(pad "AH12" smd circle
			(at -2.800096 9.99998)
			(size 0.3556 0.3556)
			(layers "F.Cu" "F.Mask" "F.Paste")
			(net "GND")
		)
		(pad "AH13" smd circle
			(at -1.999996 9.99998)
			(size 0.3556 0.3556)
			(layers "F.Cu" "F.Mask" "F.Paste")
			(net "GND")
		)
		(pad "AH14" smd circle
			(at -1.199896 9.99998)
			(size 0.3556 0.3556)
			(layers "F.Cu" "F.Mask" "F.Paste")
			(net "GND")
		)
		(pad "AH15" smd circle
			(at -0.40005 9.99998)
			(size 0.3556 0.3556)
			(layers "F.Cu" "F.Mask" "F.Paste")
			(net "PCE_VDDH")
		)
		(pad "AH16" smd circle
			(at 0.40005 9.99998)
			(size 0.3556 0.3556)
			(layers "F.Cu" "F.Mask" "F.Paste")
			(net "GND")
		)
		(pad "AH17" smd circle
			(at 1.199896 9.99998)
			(size 0.3556 0.3556)
			(layers "F.Cu" "F.Mask" "F.Paste")
			(net "GND")
		)
		(pad "AH18" smd circle
			(at 1.999996 9.99998)
			(size 0.3556 0.3556)
			(layers "F.Cu" "F.Mask" "F.Paste")
			(net "GND")
		)
		(pad "AH19" smd circle
			(at 2.800096 9.99998)
			(size 0.3556 0.3556)
			(layers "F.Cu" "F.Mask" "F.Paste")
			(net "Net_1155")
		)
		(pad "AH20" smd circle
			(at 3.599942 9.99998)
			(size 0.3556 0.3556)
			(layers "F.Cu" "F.Mask" "F.Paste")
			(net "PCIE_RST_N")
		)
		(pad "AH21" smd circle
			(at 4.400042 9.99998)
			(size 0.3556 0.3556)
			(layers "F.Cu" "F.Mask" "F.Paste")
			(net "IOC_UART_1_TX")
		)
		(pad "AH22" smd circle
			(at 5.199888 9.99998)
			(size 0.3556 0.3556)
			(layers "F.Cu" "F.Mask" "F.Paste")
			(net "IOC_GPIO_2")
		)
		(pad "AH23" smd circle
			(at 5.999988 9.99998)
			(size 0.3556 0.3556)
			(layers "F.Cu" "F.Mask" "F.Paste")
			(net "IOC_GPIO_3")
		)
		(pad "AH24" smd circle
			(at 6.800088 9.99998)
			(size 0.3556 0.3556)
			(layers "F.Cu" "F.Mask" "F.Paste")
			(net "IOC_GPIO_5")
		)
		(pad "AH25" smd circle
			(at 7.599934 9.99998)
			(size 0.3556 0.3556)
			(layers "F.Cu" "F.Mask" "F.Paste")
			(net "IOC_GPIO_6")
		)
		(pad "AH26" smd circle
			(at 8.400034 9.99998)
			(size 0.3556 0.3556)
			(layers "F.Cu" "F.Mask" "F.Paste")
			(net "IOC_UART_1_RX")
		)
		(pad "AH27" smd circle
			(at 9.19988 9.99998)
			(size 0.3556 0.3556)
			(layers "F.Cu" "F.Mask" "F.Paste")
			(net "SPARE0")
		)
		(pad "AH28" smd circle
			(at 9.99998 9.99998)
			(size 0.4064 0.4064)
			(layers "F.Cu" "F.Mask" "F.Paste")
			(net "IOC_GPIO_10")
		)
		(pad "AH29" smd circle
			(at 10.80008 9.99998)
			(size 0.4064 0.4064)
			(layers "F.Cu" "F.Mask" "F.Paste")
			(net "IOC_GPIO_22")
		)
		(pad "AH30" smd circle
			(at 11.599926 9.99998)
			(size 0.4064 0.4064)
			(layers "F.Cu" "F.Mask" "F.Paste")
			(net "IOC_GPIO_11")
		)
		(pad "AJ1" smd circle
			(at -11.599926 10.80008)
			(size 0.4064 0.4064)
			(layers "F.Cu" "F.Mask" "F.Paste")
			(net "SAS0_VDDH")
		)
		(pad "AJ2" smd circle
			(at -10.80008 10.80008)
			(size 0.4064 0.4064)
			(layers "F.Cu" "F.Mask" "F.Paste")
			(net "GND")
		)
		(pad "AJ3" smd circle
			(at -9.99998 10.80008)
			(size 0.4064 0.4064)
			(layers "F.Cu" "F.Mask" "F.Paste")
			(net "SAS0_AVDD")
		)
		(pad "AJ4" smd circle
			(at -9.19988 10.80008)
			(size 0.3556 0.3556)
			(layers "F.Cu" "F.Mask" "F.Paste")
			(net "GND")
		)
		(pad "AJ5" smd circle
			(at -8.400034 10.80008)
			(size 0.3556 0.3556)
			(layers "F.Cu" "F.Mask" "F.Paste")
			(net "GND")
		)
		(pad "AJ6" smd circle
			(at -7.599934 10.80008)
			(size 0.3556 0.3556)
			(layers "F.Cu" "F.Mask" "F.Paste")
			(net "GND")
		)
		(pad "AJ7" smd circle
			(at -6.800088 10.80008)
			(size 0.3556 0.3556)
			(layers "F.Cu" "F.Mask" "F.Paste")
			(net "PCIE_COMP_TO_SCC_0_DN")
		)
		(pad "AJ8" smd circle
			(at -5.999988 10.80008)
			(size 0.3556 0.3556)
			(layers "F.Cu" "F.Mask" "F.Paste")
			(net "PCIE_COMP_TO_SCC_1_DN")
		)
		(pad "AJ9" smd circle
			(at -5.199888 10.80008)
			(size 0.3556 0.3556)
			(layers "F.Cu" "F.Mask" "F.Paste")
			(net "GND")
		)
		(pad "AJ10" smd circle
			(at -4.400042 10.80008)
			(size 0.3556 0.3556)
			(layers "F.Cu" "F.Mask" "F.Paste")
			(net "PCIE_COMP_TO_SCC_2_DN")
		)
		(pad "AJ11" smd circle
			(at -3.599942 10.80008)
			(size 0.3556 0.3556)
			(layers "F.Cu" "F.Mask" "F.Paste")
			(net "PCIE_COMP_TO_SCC_3_DN")
		)
		(pad "AJ12" smd circle
			(at -2.800096 10.80008)
			(size 0.3556 0.3556)
			(layers "F.Cu" "F.Mask" "F.Paste")
			(net "GND")
		)
		(pad "AJ13" smd circle
			(at -1.999996 10.80008)
			(size 0.3556 0.3556)
			(layers "F.Cu" "F.Mask" "F.Paste")
			(net "PCIE_COMP_TO_SCC_4_DN")
		)
		(pad "AJ14" smd circle
			(at -1.199896 10.80008)
			(size 0.3556 0.3556)
			(layers "F.Cu" "F.Mask" "F.Paste")
			(net "PCIE_COMP_TO_SCC_5_DN")
		)
		(pad "AJ15" smd circle
			(at -0.40005 10.80008)
			(size 0.3556 0.3556)
			(layers "F.Cu" "F.Mask" "F.Paste")
			(net "GND")
		)
		(pad "AJ16" smd circle
			(at 0.40005 10.80008)
			(size 0.3556 0.3556)
			(layers "F.Cu" "F.Mask" "F.Paste")
			(net "PCIE_COMP_TO_SCC_6_DN")
		)
		(pad "AJ17" smd circle
			(at 1.199896 10.80008)
			(size 0.3556 0.3556)
			(layers "F.Cu" "F.Mask" "F.Paste")
			(net "PCIE_COMP_TO_SCC_7_DN")
		)
		(pad "AJ18" smd circle
			(at 1.999996 10.80008)
			(size 0.3556 0.3556)
			(layers "F.Cu" "F.Mask" "F.Paste")
			(net "GND")
		)
		(pad "AJ19" smd circle
			(at 2.800096 10.80008)
			(size 0.3556 0.3556)
			(layers "F.Cu" "F.Mask" "F.Paste")
			(net "Net_1156")
		)
		(pad "AJ20" smd circle
			(at 3.599942 10.80008)
			(size 0.3556 0.3556)
			(layers "F.Cu" "F.Mask" "F.Paste")
			(net "SYS_ERR_0")
		)
		(pad "AJ21" smd circle
			(at 4.400042 10.80008)
			(size 0.3556 0.3556)
			(layers "F.Cu" "F.Mask" "F.Paste")
			(net "IOC_RESET_N")
		)
		(pad "AJ22" smd circle
			(at 5.199888 10.80008)
			(size 0.3556 0.3556)
			(layers "F.Cu" "F.Mask" "F.Paste")
			(net "SPARE2")
		)
		(pad "AJ23" smd circle
			(at 5.999988 10.80008)
			(size 0.3556 0.3556)
			(layers "F.Cu" "F.Mask" "F.Paste")
			(net "SYS_DBMODE3")
		)
		(pad "AJ24" smd circle
			(at 6.800088 10.80008)
			(size 0.3556 0.3556)
			(layers "F.Cu" "F.Mask" "F.Paste")
			(net "IOC_UART_0_RX")
		)
		(pad "AJ25" smd circle
			(at 7.599934 10.80008)
			(size 0.3556 0.3556)
			(layers "F.Cu" "F.Mask" "F.Paste")
			(net "IOC_GPIO_13")
		)
		(pad "AJ26" smd circle
			(at 8.400034 10.80008)
			(size 0.3556 0.3556)
			(layers "F.Cu" "F.Mask" "F.Paste")
			(net "IOC_GPIO_1")
		)
		(pad "AJ27" smd circle
			(at 9.19988 10.80008)
			(size 0.3556 0.3556)
			(layers "F.Cu" "F.Mask" "F.Paste")
			(net "IOC_GPIO_14")
		)
		(pad "AJ28" smd circle
			(at 9.99998 10.80008)
			(size 0.4064 0.4064)
			(layers "F.Cu" "F.Mask" "F.Paste")
			(net "IOC_GPIO_20")
		)
		(pad "AJ29" smd circle
			(at 10.80008 10.80008)
			(size 0.4064 0.4064)
			(layers "F.Cu" "F.Mask" "F.Paste")
			(net "IOC_GPIO_12")
		)
		(pad "AJ30" smd circle
			(at 11.599926 10.80008)
			(size 0.4064 0.4064)
			(layers "F.Cu" "F.Mask" "F.Paste")
			(net "IOC_GPIO_4")
		)
		(pad "AK2" smd circle
			(at -10.80008 11.599926)
			(size 0.4064 0.4064)
			(layers "F.Cu" "F.Mask" "F.Paste")
			(net "GND")
		)
		(pad "AK3" smd circle
			(at -9.99998 11.599926)
			(size 0.4064 0.4064)
			(layers "F.Cu" "F.Mask" "F.Paste")
			(net "GND")
		)
		(pad "AK4" smd circle
			(at -9.19988 11.599926)
			(size 0.3556 0.3556)
			(layers "F.Cu" "F.Mask" "F.Paste")
			(net "PCIE_CLK_R_P")
		)
		(pad "AK5" smd circle
			(at -8.400034 11.599926)
			(size 0.3556 0.3556)
			(layers "F.Cu" "F.Mask" "F.Paste")
			(net "PCIE_CLK_R_N")
		)
		(pad "AK6" smd circle
			(at -7.599934 11.599926)
			(size 0.3556 0.3556)
			(layers "F.Cu" "F.Mask" "F.Paste")
			(net "PCE_AVDD")
		)
		(pad "AK7" smd circle
			(at -6.800088 11.599926)
			(size 0.3556 0.3556)
			(layers "F.Cu" "F.Mask" "F.Paste")
			(net "PCIE_COMP_TO_SCC_0_DP")
		)
		(pad "AK8" smd circle
			(at -5.999988 11.599926)
			(size 0.3556 0.3556)
			(layers "F.Cu" "F.Mask" "F.Paste")
			(net "PCIE_COMP_TO_SCC_1_DP")
		)
		(pad "AK9" smd circle
			(at -5.199888 11.599926)
			(size 0.3556 0.3556)
			(layers "F.Cu" "F.Mask" "F.Paste")
			(net "PCE_AVDD")
		)
		(pad "AK10" smd circle
			(at -4.400042 11.599926)
			(size 0.3556 0.3556)
			(layers "F.Cu" "F.Mask" "F.Paste")
			(net "PCIE_COMP_TO_SCC_2_DP")
		)
		(pad "AK11" smd circle
			(at -3.599942 11.599926)
			(size 0.3556 0.3556)
			(layers "F.Cu" "F.Mask" "F.Paste")
			(net "PCIE_COMP_TO_SCC_3_DP")
		)
		(pad "AK12" smd circle
			(at -2.800096 11.599926)
			(size 0.3556 0.3556)
			(layers "F.Cu" "F.Mask" "F.Paste")
			(net "PCE_AVDD")
		)
		(pad "AK13" smd circle
			(at -1.999996 11.599926)
			(size 0.3556 0.3556)
			(layers "F.Cu" "F.Mask" "F.Paste")
			(net "PCIE_COMP_TO_SCC_4_DP")
		)
		(pad "AK14" smd circle
			(at -1.199896 11.599926)
			(size 0.3556 0.3556)
			(layers "F.Cu" "F.Mask" "F.Paste")
			(net "PCIE_COMP_TO_SCC_5_DP")
		)
		(pad "AK15" smd circle
			(at -0.40005 11.599926)
			(size 0.3556 0.3556)
			(layers "F.Cu" "F.Mask" "F.Paste")
			(net "PCE_AVDD")
		)
		(pad "AK16" smd circle
			(at 0.40005 11.599926)
			(size 0.3556 0.3556)
			(layers "F.Cu" "F.Mask" "F.Paste")
			(net "PCIE_COMP_TO_SCC_6_DP")
		)
		(pad "AK17" smd circle
			(at 1.199896 11.599926)
			(size 0.3556 0.3556)
			(layers "F.Cu" "F.Mask" "F.Paste")
			(net "PCIE_COMP_TO_SCC_7_DP")
		)
		(pad "AK18" smd circle
			(at 1.999996 11.599926)
			(size 0.3556 0.3556)
			(layers "F.Cu" "F.Mask" "F.Paste")
			(net "PCE_AVDD")
		)
		(pad "AK19" smd circle
			(at 2.800096 11.599926)
			(size 0.3556 0.3556)
			(layers "F.Cu" "F.Mask" "F.Paste")
			(net "Net_1157")
		)
		(pad "AK20" smd circle
			(at 3.599942 11.599926)
			(size 0.3556 0.3556)
			(layers "F.Cu" "F.Mask" "F.Paste")
			(net "SYS_DBMODE1")
		)
		(pad "AK21" smd circle
			(at 4.400042 11.599926)
			(size 0.3556 0.3556)
			(layers "F.Cu" "F.Mask" "F.Paste")
			(net "SYS_DBMODE4")
		)
		(pad "AK22" smd circle
			(at 5.199888 11.599926)
			(size 0.3556 0.3556)
			(layers "F.Cu" "F.Mask" "F.Paste")
			(net "SYS_ERROR1")
		)
		(pad "AK23" smd circle
			(at 5.999988 11.599926)
			(size 0.3556 0.3556)
			(layers "F.Cu" "F.Mask" "F.Paste")
			(net "SYS_HALT0#")
		)
		(pad "AK24" smd circle
			(at 6.800088 11.599926)
			(size 0.3556 0.3556)
			(layers "F.Cu" "F.Mask" "F.Paste")
			(net "SYS_DBMODE2")
		)
		(pad "AK25" smd circle
			(at 7.599934 11.599926)
			(size 0.3556 0.3556)
			(layers "F.Cu" "F.Mask" "F.Paste")
			(net "SPARE1")
		)
		(pad "AK26" smd circle
			(at 8.400034 11.599926)
			(size 0.3556 0.3556)
			(layers "F.Cu" "F.Mask" "F.Paste")
			(net "SYS_HALT1#")
		)
		(pad "AK27" smd circle
			(at 9.19988 11.599926)
			(size 0.3556 0.3556)
			(layers "F.Cu" "F.Mask" "F.Paste")
			(net "IOC_UART_0_TX")
		)
		(pad "AK28" smd circle
			(at 9.99998 11.599926)
			(size 0.4064 0.4064)
			(layers "F.Cu" "F.Mask" "F.Paste")
			(net "IOC_GPIO_19")
		)
		(pad "AK29" smd circle
			(at 10.80008 11.599926)
			(size 0.4064 0.4064)
			(layers "F.Cu" "F.Mask" "F.Paste")
			(net "IOC_GPIO_9")
		)
		(pad "B1" smd circle
			(at -11.599926 -10.80008)
			(size 0.4064 0.4064)
			(layers "F.Cu" "F.Mask" "F.Paste")
			(net "Net_1196")
		)
		(pad "B2" smd circle
			(at -10.80008 -10.80008)
			(size 0.4064 0.4064)
			(layers "F.Cu" "F.Mask" "F.Paste")
			(net "GND")
		)
		(pad "B3" smd circle
			(at -9.99998 -10.80008)
			(size 0.4064 0.4064)
			(layers "F.Cu" "F.Mask" "F.Paste")
			(net "Net_1162")
		)
		(pad "B4" smd circle
			(at -9.19988 -10.80008)
			(size 0.3556 0.3556)
			(layers "F.Cu" "F.Mask" "F.Paste")
			(net "Net_1163")
		)
		(pad "B5" smd circle
			(at -8.400034 -10.80008)
			(size 0.3556 0.3556)
			(layers "F.Cu" "F.Mask" "F.Paste")
			(net "Net_1164")
		)
		(pad "B6" smd circle
			(at -7.599934 -10.80008)
			(size 0.3556 0.3556)
			(layers "F.Cu" "F.Mask" "F.Paste")
			(net "GND")
		)
		(pad "B7" smd circle
			(at -6.800088 -10.80008)
			(size 0.3556 0.3556)
			(layers "F.Cu" "F.Mask" "F.Paste")
			(net "ICE1_TCK")
		)
		(pad "B8" smd circle
			(at -5.999988 -10.80008)
			(size 0.3556 0.3556)
			(layers "F.Cu" "F.Mask" "F.Paste")
			(net "ICE0_TDI")
		)
		(pad "B9" smd circle
			(at -5.199888 -10.80008)
			(size 0.3556 0.3556)
			(layers "F.Cu" "F.Mask" "F.Paste")
			(net "IOC_VREF_SET")
		)
		(pad "B10" smd circle
			(at -4.400042 -10.80008)
			(size 0.3556 0.3556)
			(layers "F.Cu" "F.Mask" "F.Paste")
			(net "Net_1165")
		)
		(pad "B11" smd circle
			(at -3.599942 -10.80008)
			(size 0.3556 0.3556)
			(layers "F.Cu" "F.Mask" "F.Paste")
			(net "GND")
		)
		(pad "B12" smd circle
			(at -2.800096 -10.80008)
			(size 0.3556 0.3556)
			(layers "F.Cu" "F.Mask" "F.Paste")
			(net "AVSO_IDDTN18")
		)
		(pad "B13" smd circle
			(at -1.999996 -10.80008)
			(size 0.3556 0.3556)
			(layers "F.Cu" "F.Mask" "F.Paste")
			(net "AVSO_VREF")
		)
		(pad "B14" smd circle
			(at -1.199896 -10.80008)
			(size 0.3556 0.3556)
			(layers "F.Cu" "F.Mask" "F.Paste")
			(net "GND")
		)
		(pad "B15" smd circle
			(at -0.40005 -10.80008)
			(size 0.3556 0.3556)
			(layers "F.Cu" "F.Mask" "F.Paste")
			(net "GND")
		)
		(pad "B16" smd circle
			(at 0.40005 -10.80008)
			(size 0.3556 0.3556)
			(layers "F.Cu" "F.Mask" "F.Paste")
			(net "LSI_JTAG_EN_N")
		)
		(pad "B17" smd circle
			(at 1.199896 -10.80008)
			(size 0.3556 0.3556)
			(layers "F.Cu" "F.Mask" "F.Paste")
			(net "LSI_SCAN_EN")
		)
		(pad "B18" smd circle
			(at 1.999996 -10.80008)
			(size 0.3556 0.3556)
			(layers "F.Cu" "F.Mask" "F.Paste")
			(net "JTAG_IOC_TMS")
		)
		(pad "B19" smd circle
			(at 2.800096 -10.80008)
			(size 0.3556 0.3556)
			(layers "F.Cu" "F.Mask" "F.Paste")
			(net "XM_CS0_N")
		)
		(pad "B20" smd circle
			(at 3.599942 -10.80008)
			(size 0.3556 0.3556)
			(layers "F.Cu" "F.Mask" "F.Paste")
			(net "XM_F_RST_N")
		)
		(pad "B21" smd circle
			(at 4.400042 -10.80008)
			(size 0.3556 0.3556)
			(layers "F.Cu" "F.Mask" "F.Paste")
			(net "XM_NAND_CS_N")
		)
		(pad "B22" smd circle
			(at 5.199888 -10.80008)
			(size 0.3556 0.3556)
			(layers "F.Cu" "F.Mask" "F.Paste")
			(net "XM_OE_N")
		)
		(pad "B23" smd circle
			(at 5.999988 -10.80008)
			(size 0.3556 0.3556)
			(layers "F.Cu" "F.Mask" "F.Paste")
			(net "Net_1150")
		)
		(pad "B24" smd circle
			(at 6.800088 -10.80008)
			(size 0.3556 0.3556)
			(layers "F.Cu" "F.Mask" "F.Paste")
			(net "Net_1151")
		)
		(pad "B25" smd circle
			(at 7.599934 -10.80008)
			(size 0.3556 0.3556)
			(layers "F.Cu" "F.Mask" "F.Paste")
			(net "XM_ADDR_0")
		)
		(pad "B26" smd circle
			(at 8.400034 -10.80008)
			(size 0.3556 0.3556)
			(layers "F.Cu" "F.Mask" "F.Paste")
			(net "XM_ALE")
		)
		(pad "B27" smd circle
			(at 9.19988 -10.80008)
			(size 0.3556 0.3556)
			(layers "F.Cu" "F.Mask" "F.Paste")
			(net "XM_ADDR_1")
		)
		(pad "B28" smd circle
			(at 9.99998 -10.80008)
			(size 0.4064 0.4064)
			(layers "F.Cu" "F.Mask" "F.Paste")
			(net "XM_ADDR_6")
		)
	)
)
